# BASEBOARD_FAB2 (Tioga Pass) — schematic netlist excerpt (pin names and nets, part order shuffled) for the footprints in the layout excerpt that follows; sources: Cadence DE-HDL packaged netlist, KiCad conversion of Wiwynn_Tioga_Pass_MB.brd

R2U8  RES  20.0 1% EMPTY  pkg 0402  page 138 : A = SMB_LAN_STBY_LVC3_SCL ; B = SMB_OCP_FRU_STBY_LVC3_SCL
C9P11  CAP_A  0.1UF 16V 10% X7R  pkg 0402V  page 200 : A = P3V3_STBY ; B = GND
C4T2  CAP_A  1.0UF 6.3V 10% X6S  pkg 0402V  page 194 : A = P1V8_MCP_CPU0 ; B = GND

(kicad_pcb
	(version 20260206)
	(generator "pcbnew")
	(generator_version "10.0")
	(general
		(thickness 1.6)
		(legacy_teardrops no)
	)
	(paper "A4")
	(title_block
		(title "Wiwynn_Tioga_Pass_MB.brd")
		(comment 1 "Tioga Pass / footprints 3809-3811 of 4770")
	)
	(layers
		(0 "F.Cu" signal "TOP")
		(4 "In1.Cu" signal "L2GND")
		(6 "In2.Cu" signal "L3")
		(8 "In3.Cu" signal "L4GND")
		(10 "In4.Cu" signal "L5")
		(12 "In5.Cu" signal "L6GND")
		(14 "In6.Cu" signal "L7VCC")
		(16 "In7.Cu" signal "L8VCC")
		(18 "In8.Cu" signal "L9GND")
		(20 "In9.Cu" signal "L10")
		(22 "In10.Cu" signal "L11GND")
		(24 "In11.Cu" signal "L12")
		(26 "In12.Cu" signal "L13GND")
		(2 "B.Cu" signal "BOTTOM")
		(9 "F.Adhes" user "F.Adhesive")
		(11 "B.Adhes" user "B.Adhesive")
		(13 "F.Paste" user "Package Geometry/Pastemask Top")
		(15 "B.Paste" user "Package Geometry/Pastemask Bottom")
		(5 "F.SilkS" user "Ref Des/Silkscreen Top")
		(7 "B.SilkS" user "Ref Des/Silkscreen Bottom")
		(1 "F.Mask" user "Board Geometry/Soldermask Top")
		(3 "B.Mask" user "Board Geometry/Soldermask Bottom")
		(17 "Dwgs.User" user "User.Drawings")
		(19 "Cmts.User" user "User.Comments")
		(21 "Eco1.User" user "User.Eco1")
		(23 "Eco2.User" user "User.Eco2")
		(25 "Edge.Cuts" user "Board Geometry/Outline")
		(27 "Margin" user)
		(31 "F.CrtYd" user "Package Geometry/Place Bound Top")
		(29 "B.CrtYd" user "Package Geometry/Place Bound Bottom")
		(35 "F.Fab" user "Ref Des/Assembly Top")
		(33 "B.Fab" user "Ref Des/Assembly Bottom")
	)
	(footprint ""
		(layer "B.Cu")
		(at 395.351 -85.9155)
		(property "Reference" "R2U8"
			(at 0 0 0)
			(layer "B.SilkS")
			(hide yes)
			(effects
				(font
					(size 1.27 1.27)
				)
				(justify mirror)
			)
		)
		(property "Value" ""
			(at 0 0 0)
			(layer "B.Fab")
			(effects
				(font
					(size 1.27 1.27)
				)
				(justify mirror)
			)
		)
		(duplicate_pad_numbers_are_jumpers no)
		(fp_poly
			(pts
				(xy 0.2794 -0.1016) (xy -0.2794 -0.1016) (xy -0.2794 0.9906) (xy 0.2794 0.9906)
			)
			(stroke
				(width 0)
				(type default)
			)
			(fill no)
			(layer "B.CrtYd")
		)
		(fp_line
			(start -0.2794 -0.1016)
			(end 0.2794 -0.1016)
			(stroke
				(width 0.1)
				(type default)
			)
			(layer "B.Fab")
		)
		(fp_line
			(start -0.2794 0.9906)
			(end -0.2794 -0.1016)
			(stroke
				(width 0.1)
				(type default)
			)
			(layer "B.Fab")
		)
		(fp_line
			(start 0.2794 -0.1016)
			(end 0.2794 0.9906)
			(stroke
				(width 0.1)
				(type default)
			)
			(layer "B.Fab")
		)
		(fp_line
			(start 0.2794 0.9906)
			(end -0.2794 0.9906)
			(stroke
				(width 0.1)
				(type default)
			)
			(layer "B.Fab")
		)
		(pad "1" smd rect
			(at 0 0 180)
			(size 0.508 0.508)
			(layers "B.Cu" "B.Mask" "B.Paste")
			(net "SMB_LAN_STBY_LVC3_SCL")
		)
		(pad "2" smd rect
			(at 0 0.889 180)
			(size 0.508 0.508)
			(layers "B.Cu" "B.Mask" "B.Paste")
			(net "SMB_OCP_FRU_STBY_LVC3_SCL")
		)
		(zone
			(layer "B.Cu")
			(hatch none 0.5)
			(connect_pads
				(clearance 0)
			)
			(min_thickness 0.25)
			(keepout
				(tracks allowed)
				(vias not_allowed)
				(pads allowed)
				(copperpour not_allowed)
				(footprints allowed)
			)
			(placement
				(enabled no)
				(sheetname "")
			)
			(fill
				(thermal_gap 0.5)
				(thermal_bridge_width 0.5)
				(island_removal_mode 0)
			)
			(polygon
				(pts
					(xy 395.605 -85.6615) (xy 395.097 -85.6615) (xy 395.097 -85.2805) (xy 395.605 -85.2805)
				)
			)
		)
		(zone
			(layer "B.Cu")
			(hatch none 0.5)
			(connect_pads
				(clearance 0)
			)
			(min_thickness 0.25)
			(keepout
				(tracks not_allowed)
				(vias allowed)
				(pads allowed)
				(copperpour not_allowed)
				(footprints allowed)
			)
			(placement
				(enabled no)
				(sheetname "")
			)
			(fill
				(thermal_gap 0.5)
				(thermal_bridge_width 0.5)
				(island_removal_mode 0)
			)
			(polygon
				(pts
					(xy 395.605 -85.2805) (xy 395.097 -85.2805) (xy 395.097 -85.6615) (xy 395.605 -85.6615)
				)
			)
		)
	)
	(footprint ""
		(layer "B.Cu")
		(at 25.654 -77.978)
		(property "Reference" "C9P11"
			(at 0 0 0)
			(layer "B.SilkS")
			(hide yes)
			(effects
				(font
					(size 1.27 1.27)
				)
				(justify mirror)
			)
		)
		(property "Value" ""
			(at 0 0 0)
			(layer "B.Fab")
			(effects
				(font
					(size 1.27 1.27)
				)
				(justify mirror)
			)
		)
		(duplicate_pad_numbers_are_jumpers no)
		(fp_poly
			(pts
				(xy -0.3048 -0.1016) (xy -0.3048 0.9906) (xy 0.3048 0.9906) (xy 0.3048 -0.1016)
			)
			(stroke
				(width 0)
				(type default)
			)
			(fill no)
			(layer "B.CrtYd")
		)
		(fp_line
			(start -0.3048 -0.1016)
			(end 0.3048 -0.1016)
			(stroke
				(width 0.1)
				(type default)
			)
			(layer "B.Fab")
		)
		(fp_line
			(start -0.3048 0.9906)
			(end -0.3048 -0.1016)
			(stroke
				(width 0.1)
				(type default)
			)
			(layer "B.Fab")
		)
		(fp_line
			(start 0.3048 -0.1016)
			(end 0.3048 0.9906)
			(stroke
				(width 0.1)
				(type default)
			)
			(layer "B.Fab")
		)
		(fp_line
			(start 0.3048 0.9906)
			(end -0.3048 0.9906)
			(stroke
				(width 0.1)
				(type default)
			)
			(layer "B.Fab")
		)
		(pad "1" smd rect
			(at 0 0 180)
			(size 0.508 0.508)
			(layers "B.Cu" "B.Mask" "B.Paste")
			(net "P3V3_STBY")
		)
		(pad "2" smd rect
			(at 0 0.889 180)
			(size 0.508 0.508)
			(layers "B.Cu" "B.Mask" "B.Paste")
			(net "GND")
		)
		(zone
			(layer "B.Cu")
			(hatch none 0.5)
			(connect_pads
				(clearance 0)
			)
			(min_thickness 0.25)
			(keepout
				(tracks allowed)
				(vias not_allowed)
				(pads allowed)
				(copperpour not_allowed)
				(footprints allowed)
			)
			(placement
				(enabled no)
				(sheetname "")
			)
			(fill
				(thermal_gap 0.5)
				(thermal_bridge_width 0.5)
				(island_removal_mode 0)
			)
			(polygon
				(pts
					(xy 25.908 -77.724) (xy 25.4 -77.724) (xy 25.4 -77.343) (xy 25.908 -77.343)
				)
			)
		)
		(zone
			(layer "B.Cu")
			(hatch none 0.5)
			(connect_pads
				(clearance 0)
			)
			(min_thickness 0.25)
			(keepout
				(tracks not_allowed)
				(vias allowed)
				(pads allowed)
				(copperpour not_allowed)
				(footprints allowed)
			)
			(placement
				(enabled no)
				(sheetname "")
			)
			(fill
				(thermal_gap 0.5)
				(thermal_bridge_width 0.5)
				(island_removal_mode 0)
			)
			(polygon
				(pts
					(xy 25.908 -77.343) (xy 25.4 -77.343) (xy 25.4 -77.724) (xy 25.908 -77.724)
				)
			)
		)
	)
	(footprint ""
		(layer "B.Cu")
		(at 331.139038 -37.815266)
		(property "Reference" "C4T2"
			(at 0 0 0)
			(layer "B.SilkS")
			(hide yes)
			(effects
				(font
					(size 1.27 1.27)
				)
				(justify mirror)
			)
		)
		(property "Value" ""
			(at 0 0 0)
			(layer "B.Fab")
			(effects
				(font
					(size 1.27 1.27)
				)
				(justify mirror)
			)
		)
		(duplicate_pad_numbers_are_jumpers no)
		(fp_poly
			(pts
				(xy -0.3048 -0.1016) (xy -0.3048 0.9906) (xy 0.3048 0.9906) (xy 0.3048 -0.1016)
			)
			(stroke
				(width 0)
				(type default)
			)
			(fill no)
			(layer "B.CrtYd")
		)
		(fp_line
			(start -0.3048 -0.1016)
			(end 0.3048 -0.1016)
			(stroke
				(width 0.1)
				(type default)
			)
			(layer "B.Fab")
		)
		(fp_line
			(start -0.3048 0.9906)
			(end -0.3048 -0.1016)
			(stroke
				(width 0.1)
				(type default)
			)
			(layer "B.Fab")
		)
		(fp_line
			(start 0.3048 -0.1016)
			(end 0.3048 0.9906)
			(stroke
				(width 0.1)
				(type default)
			)
			(layer "B.Fab")
		)
		(fp_line
			(start 0.3048 0.9906)
			(end -0.3048 0.9906)
			(stroke
				(width 0.1)
				(type default)
			)
			(layer "B.Fab")
		)
		(pad "1" smd rect
			(at 0 0 180)
			(size 0.508 0.508)
			(layers "B.Cu" "B.Mask" "B.Paste")
			(net "P1V8_MCP_CPU0")
		)
		(pad "2" smd rect
			(at 0 0.889 180)
			(size 0.508 0.508)
			(layers "B.Cu" "B.Mask" "B.Paste")
			(net "GND")
		)
		(zone
			(layer "B.Cu")
			(hatch none 0.5)
			(connect_pads
				(clearance 0)
			)
			(min_thickness 0.25)
			(keepout
				(tracks allowed)
				(vias not_allowed)
				(pads allowed)
				(copperpour not_allowed)
				(footprints allowed)
			)
			(placement
				(enabled no)
				(sheetname "")
			)
			(fill
				(thermal_gap 0.5)
				(thermal_bridge_width 0.5)
				(island_removal_mode 0)
			)
			(polygon
				(pts
					(xy 331.393038 -37.561266) (xy 330.885038 -37.561266) (xy 330.885038 -37.180266) (xy 331.393038 -37.180266)
				)
			)
		)
		(zone
			(layer "B.Cu")
			(hatch none 0.5)
			(connect_pads
				(clearance 0)
			)
			(min_thickness 0.25)
			(keepout
				(tracks not_allowed)
				(vias allowed)
				(pads allowed)
				(copperpour not_allowed)
				(footprints allowed)
			)
			(placement
				(enabled no)
				(sheetname "")
			)
			(fill
				(thermal_gap 0.5)
				(thermal_bridge_width 0.5)
				(island_removal_mode 0)
			)
			(polygon
				(pts
					(xy 331.393038 -37.180266) (xy 330.885038 -37.180266) (xy 330.885038 -37.561266) (xy 331.393038 -37.561266)
				)
			)
		)
	)
)
